FILE_TYPE = CONNECTIVITY;
{Allegro Design Entry HDL 16.6-p007 (v16-6-112F) 10/10/2012}
"PAGE_NUMBER" = 255;
0"NC";
1"GND\g";
2"GND\g";
3"GND\g";
4"GND\g";
5"GND\g";
6"P5V_VGA_D\g";
7"GND\g";
8"GND\g";
9"GND\g";
10"GND\g";
11"P5V_VGA_D\g";
12"GND\g";
13"GND\g";
14"GND\g";
15"GND\g";
16"GND\g";
17"GND\g";
18"GND\g";
19"P5V\g";
20"GND\g";
21"GND\g";
22"GND\g";
23"GND\g";
24"GND\g";
25"GND\g";
26"P3V3\g";
27"P5V_VGA_D\g";
28"GND\g";
29"GND\g";
30"P5V_VGA_D\g";
31"P3V3\g";
32"GND\g";
33"GND\g";
34"P5V_VGA_D\g";
35"GND\g";
36"GND\g";
37"GND\g";
38"P5V_VGA_D\g";
39"V_IO_G_J";
40"V_IO_VSYNC_J";
41"V_IBMC_5V_DDC_SDA_J";
42"BMC_VGA_RED";
43"BMC_VGA_GREEN";
44"BMC_VGA_BLUE";
45"V_IO_B_J";
46"VGA_REAR_HSYNC_S";
47"V_IO_R_J";
48"V_IO_B_J";
49"V_IBMC_5V_DDC_SCL_J";
50"V_IBMC_5V_DDC_SDA_J";
51"I2C_BMC_VGA_DDC_SDA";
52"I2C_BMC_VGA_DDC_SDA_G";
53"V_IO_B_J";
54"BMC_VGA_VSYNC";
55"V_IO_R_J";
56"V_IO_HSYNC_J";
57"P5V_VGA";
58"V_IO_HSYNC_J";
59"I2C_BMC_VGA_DDC_SCL";
60"Q25W1_GATE";
61"Q25W2_GATE";
62"BMC_VGA_HSYNC";
63"V_IO_VSYNC_J";
64"P5V_VGA";
65"V_IBMC_5V_DDC_SCL_J";
66"V_IBMC_5V_DDC_SDA_J";
67"V_IO_VSYNC_J";
68"V_IO_G_J";
69"V_IBMC_5V_DDC_SCL_J";
70"V_IO_B_J";
71"V_IO_G_J";
72"V_IO_R_J";
73"I2C_BMC_VGA_DDC_SCL_G";
74"VGA_REAR_VSYNC_S";
75"V_IO_HSYNC_J";
76"V_IO_G_J";
77"V_IO_R_J";
%"GND"
"1","(-4100,3200)","0","mstr_symbols","I10";
;
CDS_LIB"mstr_symbols"
VOLTAGE"0.0V"
SIZE"1B"
BODY_TYPE"PLUMBING"
HDL_POWER"GND";
"A\NAC"1;
%"CAP"
"1","(-4500,3450)","0","mstr_discrete","I11";
;
CDS_SEC"1"
LOCATION"C25W73"
VOLTAGE"50V"
TOLERANCE"5%"
VALUE"12.0PF"
MATERIAL"COG"
PART_NUMBER"A36095-043"
PACK_TYPE"0402LF"
GROUP"AST2500"
CDS_LOCATION"C25W73"
CDS_LIB"mstr_discrete"
ROOM"LBG"
BOM_COST"LBG_UART"
SEC_TYPE"0402LF"
SEC"1";
"A"
$PN"1"43;
"B"
$PN"2"37;
%"U74AHCT1G125G-AL5-R-GP-U"
"1","(-4350,5100)","0","w_hdl","I111";
;
CDS_SEC"1"
CDS_LOCATION"U25W7"
LOCATION"U25W7"
VALUE"U74AHCT1G125G-AL5-R-GP-U"
GROUP"AST2500"
CDS_LMAN_SYM_OUTLINE"-150,150,150,-150"
CDS_LIB"w_hdl"
PART_NUMBER"73.1G125.D0G"
SEC_TYPE"TTL-G4"
SEC"1"
PACK_TYPE"TTL-G4";
"VCC"
$PN"5"11;
"Y"
$PN"4"46;
"GND"
$PN"3"5;
"A"
$PN"2"62;
"OE# \B"
$PN"1"4;
%"U74AHCT1G125G-AL5-R-GP-U"
"1","(-4350,4550)","0","w_hdl","I112";
;
CDS_SEC"1"
CDS_LOCATION"U25W8"
VALUE"U74AHCT1G125G-AL5-R-GP-U"
LOCATION"U25W8"
GROUP"AST2500"
CDS_LMAN_SYM_OUTLINE"-150,150,150,-150"
CDS_LIB"w_hdl"
PART_NUMBER"73.1G125.D0G"
SEC_TYPE"TTL-G4"
SEC"1"
PACK_TYPE"TTL-G4";
"VCC"
$PN"5"6;
"Y"
$PN"4"74;
"GND"
$PN"3"2;
"A"
$PN"2"54;
"OE# \B"
$PN"1"3;
%"GND"
"1","(-4750,4350)","0","mstr_symbols","I113";
;
SIZE"1B"
VOLTAGE"0.0V"
CDS_LIB"mstr_symbols"
BODY_TYPE"PLUMBING"
HDL_POWER"GND";
"A\NAC"2;
%"GND"
"1","(-4750,4600)","0","mstr_symbols","I114";
;
SIZE"1B"
VOLTAGE"0.0V"
CDS_LIB"mstr_symbols"
BODY_TYPE"PLUMBING"
HDL_POWER"GND";
"A\NAC"3;
%"GND"
"1","(-4750,5150)","0","mstr_symbols","I115";
;
CDS_LIB"mstr_symbols"
VOLTAGE"0.0V"
SIZE"1B"
BODY_TYPE"PLUMBING"
HDL_POWER"GND";
"A\NAC"4;
%"GND"
"1","(-4750,4900)","0","mstr_symbols","I116";
;
CDS_LIB"mstr_symbols"
VOLTAGE"0.0V"
SIZE"1B"
BODY_TYPE"PLUMBING"
HDL_POWER"GND";
"A\NAC"5;
%"W_VCC_CIRCLE"
"1","(-3850,4700)","0","w_power","I117";
;
HDL_POWER"P5V_VGA_D"
CDS_LMAN_SYM_OUTLINE"-100,100,100,-100"
CDS_LIB"w_power"
BODY_TYPE"PLUMBING";
"VCC_CIRCLE \B"6;
%"CAP_A"
"1","(-3500,4650)","1","dev_discrete","I118";
;
PART_NUMBER"A36096-030"
PACK_TYPE"0402V"
GROUP"AST2500"
VOLTAGE"16V"
LOCATION"C25W90"
VALUE"0.1UF"
MATERIAL"X7R"
TOLERANCE"10%"
SEC"1"
SEC_TYPE"0402V"
CDS_SEC"1"
CDS_LIB"dev_discrete"
BOM_COST"PROC_SIDEBAND"
ROOM"PROC_SIDEBAND"
CDS_LOCATION"C25W90";
"B"
$PN"2"7;
"A"
$PN"1"6;
%"GND"
"1","(-3200,4550)","0","mstr_symbols","I119";
;
SIZE"1B"
VOLTAGE"0.0V"
CDS_LIB"mstr_symbols"
BODY_TYPE"PLUMBING"
HDL_POWER"GND";
"A\NAC"7;
%"CAP"
"1","(-4100,3450)","0","mstr_discrete","I12";
;
CDS_SEC"1"
GROUP"AST2500"
LOCATION"C25W74"
PACK_TYPE"0402LF"
MATERIAL"COG"
TOLERANCE"5%"
PART_NUMBER"A36095-043"
VOLTAGE"50V"
VALUE"12.0PF"
CDS_LOCATION"C25W74"
CDS_LIB"mstr_discrete"
ROOM"LBG"
BOM_COST"LBG_UART"
SEC_TYPE"0402LF"
SEC"1";
"A"
$PN"1"42;
"B"
$PN"2"1;
%"RB551V30-GP"
"1","(-4775,2750)","0","w_hdl","I128";
;
CDS_SEC"1"
CDS_LOCATION"D25W8"
GROUP"AST2500"
LOCATION"D25W8"
VALUE"RB551V30-GP"
PACK_TYPE"DISCRET-G"
SEC"1"
SEC_TYPE"DISCRET-G"
PART_NUMBER"83.R5003.H8H"
CDS_LIB"w_hdl"
CDS_LMAN_SYM_OUTLINE"-75,50,75,-50";
"ANODE"
$PN"A"19;
"CATHODE"
$PN"K"38;
%"DIODEAC_DUAL_ARRAY"
"7","(-7000,5750)","0","mstr_discrete","I129";
;
CDS_SEC"1"
LOCATION"CR25W1"
MATERIAL"IC"
VALUE"ESD3V3U4ULC"
PART_NUMBER"G18435-001"
GROUP"AST2500"
CDS_LOCATION"CR25W1"
CDS_LIB"mstr_discrete"
ROOM"USB_REAR"
SEC"1"
SEC_TYPE"SM9"
PACK_TYPE"SM9"
BOM_COST"MIO_USB";
"AC3"
$PN"5"0;
"AC2"
$PN"4"47;
"AC1"
$PN"2"39;
"AC0"
$PN"1"48;
"OUT3"
$PN"6"0;
"OUT2"
$PN"7"47;
"OUT1"
$PN"8"39;
"OUT0"
$PN"9"48;
"GND<0>"
$PN"3"8;
%"GND"
"1","(-6600,5500)","0","mstr_symbols","I130";
;
SIZE"1B"
VOLTAGE"0.0V"
CDS_LIB"mstr_symbols"
BODY_TYPE"PLUMBING"
HDL_POWER"GND";
"A\NAC"8;
%"DIODEAC_DUAL_ARRAY"
"7","(-4350,5750)","0","mstr_discrete","I131";
;
CDS_SEC"1"
LOCATION"CR25W2"
VALUE"ESD3V3U4ULC"
MATERIAL"IC"
GROUP"AST2500"
PART_NUMBER"G18435-001"
CDS_LOCATION"CR25W2"
BOM_COST"MIO_USB"
PACK_TYPE"SM9"
SEC_TYPE"SM9"
SEC"1"
ROOM"USB_REAR"
CDS_LIB"mstr_discrete";
"AC3"
$PN"5"58;
"AC2"
$PN"4"63;
"AC1"
$PN"2"49;
"AC0"
$PN"1"50;
"OUT3"
$PN"6"58;
"OUT2"
$PN"7"63;
"OUT1"
$PN"8"49;
"OUT0"
$PN"9"50;
"GND<0>"
$PN"3"9;
%"GND"
"1","(-3950,5500)","0","mstr_symbols","I132";
;
CDS_LIB"mstr_symbols"
VOLTAGE"0.0V"
SIZE"1B"
BODY_TYPE"PLUMBING"
HDL_POWER"GND";
"A\NAC"9;
%"GND"
"1","(-3200,5100)","0","mstr_symbols","I133";
;
SIZE"1B"
VOLTAGE"0.0V"
CDS_LIB"mstr_symbols"
BODY_TYPE"PLUMBING"
HDL_POWER"GND";
"A\NAC"10;
%"CAP_A"
"1","(-3500,5200)","1","dev_discrete","I134";
;
VALUE"0.1UF"
PACK_TYPE"0402V"
VOLTAGE"16V"
MATERIAL"X7R"
LOCATION"C25P80"
TOLERANCE"10%"
PART_NUMBER"A36096-030"
GROUP"AST2500"
CDS_LOCATION"C25P80"
SEC"1"
SEC_TYPE"0402V"
CDS_SEC"1"
CDS_LIB"dev_discrete"
BOM_COST"PROC_SIDEBAND"
ROOM"PROC_SIDEBAND";
"B"
$PN"2"10;
"A"
$PN"1"11;
%"W_VCC_CIRCLE"
"1","(-3850,5250)","0","w_power","I135";
;
HDL_POWER"P5V_VGA_D"
CDS_LMAN_SYM_OUTLINE"-100,100,100,-100"
CDS_LIB"w_power"
BODY_TYPE"PLUMBING";
"VCC_CIRCLE \B"11;
%"SMC-CON13-GP"
"1","(-9225,2725)","0","w_hdl","I136";
;
CDS_SEC"1"
CDS_LOCATION"J25W1"
GROUP"AST2500"
VALUE"SMC-CON13-GP"
LOCATION"J25W1"
PACK_TYPE"CONN-GC2"
SEC"1"
SEC_TYPE"CONN-GC2"
CDS_LMAN_SYM_OUTLINE"-75,425,75,-425"
CDS_LIB"w_hdl"
PART_NUMBER"021.D0181.0113";
"PTH2"
$PN"PTH2"12;
"PTH1"
$PN"PTH1"13;
"13"
$PN"13"64;
"12"
$PN"12"65;
"11"
$PN"11"66;
"10"
$PN"10"18;
"9"
$PN"9"56;
"8"
$PN"8"17;
"7"
$PN"7"67;
"6"
$PN"6"16;
"5"
$PN"5"53;
"4"
$PN"4"15;
"3"
$PN"3"68;
"2"
$PN"2"14;
"1"
$PN"1"55;
%"GND"
"1","(-8750,2250)","0","mstr_symbols","I137";
;
SIZE"1B"
VOLTAGE"0.0V"
CDS_LIB"mstr_symbols"
BODY_TYPE"PLUMBING"
HDL_POWER"GND";
"A\NAC"12;
%"GND"
"1","(-8750,3100)","0","mstr_symbols","I138";
;
SIZE"1B"
VOLTAGE"0.0V"
CDS_LIB"mstr_symbols"
BODY_TYPE"PLUMBING"
HDL_POWER"GND";
"A\NAC"13;
%"GND"
"1","(-8800,2950)","1","mstr_symbols","I139";
;
CDS_LIB"mstr_symbols"
VOLTAGE"0.0V"
SIZE"1B"
BODY_TYPE"PLUMBING"
HDL_POWER"GND";
"A\NAC"14;
%"GND"
"1","(-8800,2850)","1","mstr_symbols","I140";
;
CDS_LIB"mstr_symbols"
VOLTAGE"0.0V"
SIZE"1B"
BODY_TYPE"PLUMBING"
HDL_POWER"GND";
"A\NAC"15;
%"GND"
"1","(-8800,2750)","1","mstr_symbols","I141";
;
CDS_LIB"mstr_symbols"
VOLTAGE"0.0V"
SIZE"1B"
BODY_TYPE"PLUMBING"
HDL_POWER"GND";
"A\NAC"16;
%"GND"
"1","(-8800,2650)","1","mstr_symbols","I142";
;
CDS_LIB"mstr_symbols"
VOLTAGE"0.0V"
SIZE"1B"
BODY_TYPE"PLUMBING"
HDL_POWER"GND";
"A\NAC"17;
%"GND"
"1","(-8800,2550)","1","mstr_symbols","I144";
;
CDS_LIB"mstr_symbols"
VOLTAGE"0.0V"
SIZE"1B"
BODY_TYPE"PLUMBING"
HDL_POWER"GND";
"A\NAC"18;
%"P5V"
"1","(-5300,2850)","0","mstr_symbols","I145";
;
CDS_LIB"mstr_symbols"
SIZE"1B"
VOLTAGE"+5.0V"
BODY_TYPE"PLUMBING"
HDL_POWER"P5V";
"G\NAC"19;
%"CAP"
"1","(-2350,3450)","0","mstr_discrete","I16";
;
CDS_SEC"1"
CDS_LOCATION"C25W77"
TOLERANCE"5%"
VALUE"12.0PF"
PACK_TYPE"0402LF"
MATERIAL"COG"
LOCATION"C25W77"
PART_NUMBER"A36095-043"
VOLTAGE"50V"
GROUP"AST2500"
BOM_COST"LBG_UART"
ROOM"LBG"
CDS_LIB"mstr_discrete"
SEC_TYPE"0402LF"
SEC"1";
"A"
$PN"1"77;
"B"
$PN"2"20;
%"GND"
"1","(-2350,3200)","0","mstr_symbols","I17";
;
SIZE"1B"
VOLTAGE"0.0V"
CDS_LIB"mstr_symbols"
BODY_TYPE"PLUMBING"
HDL_POWER"GND";
"A\NAC"20;
%"CAP"
"1","(-2700,3450)","0","mstr_discrete","I18";
;
CDS_SEC"1"
CDS_LOCATION"C25W76"
GROUP"AST2500"
VOLTAGE"50V"
PACK_TYPE"0402LF"
MATERIAL"COG"
TOLERANCE"5%"
LOCATION"C25W76"
VALUE"12.0PF"
PART_NUMBER"A36095-043"
SEC"1"
SEC_TYPE"0402LF"
CDS_LIB"mstr_discrete"
BOM_COST"LBG_UART"
ROOM"LBG";
"A"
$PN"1"76;
"B"
$PN"2"21;
%"GND"
"1","(-2700,3200)","0","mstr_symbols","I19";
;
CDS_LIB"mstr_symbols"
SIZE"1B"
VOLTAGE"0.0V"
BODY_TYPE"PLUMBING"
HDL_POWER"GND";
"A\NAC"21;
%"GND"
"1","(-3050,3200)","0","mstr_symbols","I20";
;
CDS_LIB"mstr_symbols"
SIZE"1B"
VOLTAGE"0.0V"
BODY_TYPE"PLUMBING"
HDL_POWER"GND";
"A\NAC"22;
%"CAP"
"1","(-3050,3450)","0","mstr_discrete","I21";
;
CDS_SEC"1"
CDS_LOCATION"C25W75"
VALUE"12.0PF"
PACK_TYPE"0402LF"
VOLTAGE"50V"
MATERIAL"COG"
TOLERANCE"5%"
LOCATION"C25W75"
PART_NUMBER"A36095-043"
GROUP"AST2500"
SEC"1"
SEC_TYPE"0402LF"
CDS_LIB"mstr_discrete"
BOM_COST"LBG_UART"
ROOM"LBG";
"A"
$PN"1"45;
"B"
$PN"2"22;
%"RES"
"2","(-6350,2550)","2","mstr_discrete","I22";
;
CDS_SEC"1"
$SEC"1"
CDS_LOCATION"R25W128"
GROUP"AST2500"
LOCATION"R25W128"
VALUE"150.0"
TOLERANCE"1%"
WATTAGE"1/16W"
MATERIAL"CHIP"
PART_NUMBER"G21796-009"
PACK_TYPE"0402"
CDS_LIB"mstr_discrete"
BOM_COST"PROC_SIDEBAND"
ROOM"PROC_SIDEBAND";
"A"
$PN"1"72;
"B"
$PN"2"23;
%"GND"
"1","(-6350,2300)","0","mstr_symbols","I23";
;
CDS_LIB"mstr_symbols"
SIZE"1B"
VOLTAGE"0.0V"
BODY_TYPE"PLUMBING"
HDL_POWER"GND";
"A\NAC"23;
%"RES"
"2","(-6700,2550)","2","mstr_discrete","I24";
;
CDS_SEC"1"
$SEC"1"
CDS_LOCATION"R25W127"
GROUP"AST2500"
VALUE"150.0"
PART_NUMBER"G21796-009"
WATTAGE"1/16W"
LOCATION"R25W127"
TOLERANCE"1%"
PACK_TYPE"0402"
MATERIAL"CHIP"
CDS_LIB"mstr_discrete"
BOM_COST"PROC_SIDEBAND"
ROOM"PROC_SIDEBAND";
"A"
$PN"1"71;
"B"
$PN"2"24;
%"GND"
"1","(-6700,2300)","0","mstr_symbols","I25";
;
CDS_LIB"mstr_symbols"
SIZE"1B"
VOLTAGE"0.0V"
BODY_TYPE"PLUMBING"
HDL_POWER"GND";
"A\NAC"24;
%"RES"
"2","(-7050,2550)","2","mstr_discrete","I26";
;
CDS_SEC"1"
$SEC"1"
CDS_LOCATION"R25W126"
GROUP"AST2500"
TOLERANCE"1%"
VALUE"150.0"
PART_NUMBER"G21796-009"
PACK_TYPE"0402"
MATERIAL"CHIP"
WATTAGE"1/16W"
LOCATION"R25W126"
CDS_LIB"mstr_discrete"
BOM_COST"PROC_SIDEBAND"
ROOM"PROC_SIDEBAND";
"A"
$PN"1"70;
"B"
$PN"2"25;
%"GND"
"1","(-7050,2300)","0","mstr_symbols","I27";
;
CDS_LIB"mstr_symbols"
SIZE"1B"
VOLTAGE"0.0V"
BODY_TYPE"PLUMBING"
HDL_POWER"GND";
"A\NAC"25;
%"P3V3"
"1","(-8200,5550)","0","mstr_symbols","I29";
;
VOLTAGE"3.3V"
SIZE"1B"
CDS_LIB"mstr_symbols"
BODY_TYPE"PLUMBING"
HDL_POWER"P3V3";
"G\NAC"26;
%"RES"
"2","(-8200,5300)","0","mstr_discrete","I30";
;
VALUE"4.75K"
TOLERANCE"1%"
WATTAGE"1/16W"
MATERIAL"CHIP"
PART_NUMBER"G21796-072"
PACK_TYPE"0402"
LOCATION"R25W131"
GROUP"AST2500"
CDS_SEC"1"
CDS_LIB"mstr_discrete"
ROOM"CPU_FANS"
SEC"1"
SEC_TYPE"0402"
BOM_COST"SM_THERM"
CDS_LOCATION"R25W131";
"A"
$PN"1"26;
"B"
$PN"2"60;
%"RES"
"2","(-7750,4950)","0","mstr_discrete","I31";
;
CDS_SEC"1"
CDS_LOCATION"R25W132"
PART_NUMBER"G21796-072"
WATTAGE"1/16W"
MATERIAL"CHIP"
VALUE"4.75K"
PACK_TYPE"0402"
TOLERANCE"1%"
GROUP"AST2500"
LOCATION"R25W132"
CDS_LIB"mstr_discrete"
ROOM"CPU_FANS"
BOM_COST"SM_THERM"
SEC"1"
SEC_TYPE"0402";
"A"
$PN"1"27;
"B"
$PN"2"73;
%"W_VCC_CIRCLE"
"1","(-7750,5150)","0","w_power","I32";
;
HDL_POWER"P5V_VGA_D"
CDS_LMAN_SYM_OUTLINE"-100,100,100,-100"
CDS_LIB"w_power"
BODY_TYPE"PLUMBING";
"VCC_CIRCLE \B"27;
%"RES"
"1","(-6800,4750)","0","mstr_discrete","I34";
;
CDS_SEC"1"
GROUP"AST2500"
LOCATION"R25W133"
PART_NUMBER"G21796-074"
PACK_TYPE"0402"
MATERIAL"CHIP"
WATTAGE"1/16W"
VALUE"33.2"
TOLERANCE"1%"
SEC_TYPE"0402"
SEC"1"
CDS_LIB"mstr_discrete"
CDS_LOCATION"R25W133";
"B"
$PN"2"69;
"A"
$PN"1"73;
%"CAP"
"2","(-6550,4550)","3","mstr_discrete","I35";
;
CDS_SEC"1"
CDS_LOCATION"C25W78"
PART_NUMBER"A36095-026"
PACK_TYPE"0402LF"
LOCATION"C25W78"
VOLTAGE"50V"
MATERIAL"COG"
TOLERANCE"5%"
VALUE"100.0PF"
GROUP"AST2500"
SEC"1"
SEC_TYPE"0402LF"
CDS_LIB"mstr_discrete"
ROOM"PVPP_KLM_VR"
BOM_COST"PVPP_KLM_VR"
REUSE_ID"27";
"A"
$PN"1"69;
"B"
$PN"2"28;
%"GND"
"1","(-6550,4350)","0","mstr_symbols","I36";
;
CDS_LIB"mstr_symbols"
VOLTAGE"0.0V"
SIZE"1B"
BODY_TYPE"PLUMBING"
HDL_POWER"GND";
"A\NAC"28;
%"RES"
"1","(-6800,3500)","0","mstr_discrete","I38";
;
CDS_SEC"1"
GROUP"AST2500"
LOCATION"R25W136"
PACK_TYPE"0402"
PART_NUMBER"G21796-074"
VALUE"33.2"
TOLERANCE"1%"
MATERIAL"CHIP"
WATTAGE"1/16W"
CDS_LIB"mstr_discrete"
SEC"1"
SEC_TYPE"0402"
CDS_LOCATION"R25W136";
"B"
$PN"2"41;
"A"
$PN"1"52;
%"CAP"
"2","(-6550,3300)","3","mstr_discrete","I39";
;
CDS_SEC"1"
CDS_LOCATION"C25W79"
TOLERANCE"5%"
VOLTAGE"50V"
MATERIAL"COG"
PACK_TYPE"0402LF"
PART_NUMBER"A36095-026"
VALUE"100.0PF"
LOCATION"C25W79"
GROUP"AST2500"
REUSE_ID"27"
BOM_COST"PVPP_KLM_VR"
ROOM"PVPP_KLM_VR"
CDS_LIB"mstr_discrete"
SEC_TYPE"0402LF"
SEC"1";
"A"
$PN"1"41;
"B"
$PN"2"29;
%"GND"
"1","(-6550,3100)","0","mstr_symbols","I40";
;
CDS_LIB"mstr_symbols"
VOLTAGE"0.0V"
SIZE"1B"
BODY_TYPE"PLUMBING"
HDL_POWER"GND";
"A\NAC"29;
%"W_VCC_CIRCLE"
"1","(-7750,3900)","0","w_power","I41";
;
HDL_POWER"P5V_VGA_D"
CDS_LIB"w_power"
CDS_LMAN_SYM_OUTLINE"-100,100,100,-100"
BODY_TYPE"PLUMBING";
"VCC_CIRCLE \B"30;
%"P3V3"
"1","(-8200,4300)","0","mstr_symbols","I42";
;
CDS_LIB"mstr_symbols"
SIZE"1B"
VOLTAGE"3.3V"
BODY_TYPE"PLUMBING"
HDL_POWER"P3V3";
"G\NAC"31;
%"RES"
"2","(-8200,4050)","0","mstr_discrete","I43";
;
LOCATION"R25W134"
PART_NUMBER"G21796-072"
TOLERANCE"1%"
VALUE"4.75K"
WATTAGE"1/16W"
MATERIAL"CHIP"
PACK_TYPE"0402"
GROUP"AST2500"
BOM_COST"SM_THERM"
SEC_TYPE"0402"
SEC"1"
ROOM"CPU_FANS"
CDS_LIB"mstr_discrete"
CDS_SEC"1"
CDS_LOCATION"R25W134";
"A"
$PN"1"31;
"B"
$PN"2"61;
%"RES"
"2","(-7750,3700)","0","mstr_discrete","I44";
;
CDS_SEC"1"
$SEC"1"
CDS_LOCATION"R25W135"
WATTAGE"1/16W"
TOLERANCE"1%"
PACK_TYPE"0402"
MATERIAL"CHIP"
PART_NUMBER"G21796-072"
GROUP"AST2500"
LOCATION"R25W135"
VALUE"4.75K"
BOM_COST"SM_THERM"
ROOM"CPU_FANS"
CDS_LIB"mstr_discrete";
"A"
$PN"1"30;
"B"
$PN"2"52;
%"RES"
"1","(-3250,5000)","0","mstr_discrete","I49";
;
CDS_SEC"1"
GROUP"AST2500"
PACK_TYPE"0402"
WATTAGE"1/16W"
TOLERANCE"1%"
LOCATION"R25W138"
PART_NUMBER"G21796-074"
MATERIAL"CHIP"
VALUE"33.2"
CDS_LOCATION"R25W138"
CDS_LIB"mstr_discrete"
ROOM"PROC_TRANSLATORS"
SEC_TYPE"0402"
BOM_COST"PROC_SIDEBAND"
SEC"1";
"B"
$PN"2"75;
"A"
$PN"1"46;
%"RES"
"1","(-3250,4450)","0","mstr_discrete","I59";
;
CDS_SEC"1"
LOCATION"R25W139"
PART_NUMBER"G21796-074"
GROUP"AST2500"
MATERIAL"CHIP"
VALUE"33.2"
PACK_TYPE"0402"
TOLERANCE"1%"
WATTAGE"1/16W"
CDS_LIB"mstr_discrete"
ROOM"PROC_TRANSLATORS"
SEC_TYPE"0402"
BOM_COST"PROC_SIDEBAND"
SEC"1"
CDS_LOCATION"R25W139";
"B"
$PN"2"40;
"A"
$PN"1"74;
%"CAP"
"1","(-2750,4850)","0","mstr_discrete","I60";
;
CDS_SEC"1"
TOLERANCE"5%"
VALUE"10.0PF"
VOLTAGE"50V"
LOCATION"C25W81"
MATERIAL"COG"
PART_NUMBER"A36094-025"
GROUP"AST2500"
PACK_TYPE"0402LF"
ROOM"BMC_VOLT_MONITOR"
SEC"1"
BOM_COST"SM_HM"
SEC_TYPE"0402LF"
CDS_LIB"mstr_discrete"
CDS_LOCATION"C25W81";
"A"
$PN"1"75;
"B"
$PN"2"32;
%"GND"
"1","(-2750,4650)","0","mstr_symbols","I61";
;
CDS_LIB"mstr_symbols"
VOLTAGE"0.0V"
SIZE"1B"
BODY_TYPE"PLUMBING"
HDL_POWER"GND";
"A\NAC"32;
%"CAP"
"1","(-2750,4300)","0","mstr_discrete","I62";
;
CDS_SEC"1"
PACK_TYPE"0402LF"
PART_NUMBER"A36094-025"
MATERIAL"COG"
TOLERANCE"5%"
VOLTAGE"50V"
VALUE"10.0PF"
LOCATION"C25W82"
GROUP"AST2500"
CDS_LIB"mstr_discrete"
SEC_TYPE"0402LF"
BOM_COST"SM_HM"
SEC"1"
ROOM"BMC_VOLT_MONITOR"
CDS_LOCATION"C25W82";
"A"
$PN"1"40;
"B"
$PN"2"33;
%"GND"
"1","(-2750,4100)","0","mstr_symbols","I63";
;
SIZE"1B"
VOLTAGE"0.0V"
CDS_LIB"mstr_symbols"
BODY_TYPE"PLUMBING"
HDL_POWER"GND";
"A\NAC"33;
%"CAP"
"1","(-4900,3450)","0","mstr_discrete","I7";
;
CDS_SEC"1"
GROUP"AST2500"
VALUE"12.0PF"
PART_NUMBER"A36095-043"
PACK_TYPE"0402LF"
VOLTAGE"50V"
TOLERANCE"5%"
MATERIAL"COG"
LOCATION"C25W72"
CDS_LOCATION"C25W72"
SEC"1"
SEC_TYPE"0402LF"
BOM_COST"LBG_UART"
ROOM"LBG"
CDS_LIB"mstr_discrete";
"A"
$PN"1"44;
"B"
$PN"2"36;
%"W_VCC_CIRCLE"
"1","(-2300,2950)","0","w_power","I72";
;
HDL_POWER"P5V_VGA_D"
CDS_LIB"w_power"
CDS_LMAN_SYM_OUTLINE"-100,100,100,-100"
BODY_TYPE"PLUMBING";
"VCC_CIRCLE \B"34;
%"CAP_A"
"1","(-3200,2350)","0","dev_discrete","I74";
;
GROUP"AST2500"
PACK_TYPE"0402V"
VOLTAGE"16V"
PART_NUMBER"A36096-030"
VALUE"0.1UF"
TOLERANCE"10%"
MATERIAL"X7R"
LOCATION"C25P83"
SEC"1"
SEC_TYPE"0402V"
CDS_SEC"1"
CDS_LIB"dev_discrete"
BOM_COST"PROC_SIDEBAND"
ROOM"PROC_SIDEBAND"
CDS_LOCATION"C25P83";
"B"
$PN"2"35;
"A"
$PN"1"57;
%"GND"
"1","(-3200,2100)","0","mstr_symbols","I75";
;
CDS_LIB"mstr_symbols"
VOLTAGE"0.0V"
SIZE"1B"
BODY_TYPE"PLUMBING"
HDL_POWER"GND";
"A\NAC"35;
%"IND-68NH-15-GP"
"1","(-3650,3600)","1","w_hdl","I76";
;
CDS_SEC"1"
CDS_LOCATION"L25W1"
LOCATION"L25W1"
RATED"300MA"
PACK_SIZE"DCR=800MOHM"
VALUE"IND-68NH-15-GP"
ATTRIBUTE"68NH"
GROUP"AST2500"
PACK_TYPE"DISCRET-GC1"
SEC"1"
SEC_TYPE"DISCRET-GC1"
PART_NUMBER"68.6803N.10D"
CDS_LIB"w_hdl"
CDS_LMAN_SYM_OUTLINE"-50,100,50,-100";
"2"
$PN"2"45;
"1"
$PN"1"44;
%"IND-68NH-15-GP"
"1","(-3650,3750)","1","w_hdl","I77";
;
CDS_SEC"1"
CDS_LOCATION"L25W2"
ATTRIBUTE"68NH"
RATED"300MA"
VALUE"IND-68NH-15-GP"
PACK_SIZE"DCR=800MOHM"
LOCATION"L25W2"
GROUP"AST2500"
CDS_LMAN_SYM_OUTLINE"-50,100,50,-100"
CDS_LIB"w_hdl"
PART_NUMBER"68.6803N.10D"
SEC_TYPE"DISCRET-GC1"
SEC"1"
PACK_TYPE"DISCRET-GC1";
"2"
$PN"2"76;
"1"
$PN"1"43;
%"IND-68NH-15-GP"
"1","(-3600,3900)","1","w_hdl","I78";
;
CDS_SEC"1"
CDS_LOCATION"L25W3"
VALUE"IND-68NH-15-GP"
PACK_SIZE"DCR=800MOHM"
GROUP"AST2500"
LOCATION"L25W3"
ATTRIBUTE"68NH"
RATED"300MA"
CDS_LMAN_SYM_OUTLINE"-50,100,50,-100"
CDS_LIB"w_hdl"
PART_NUMBER"68.6803N.10D"
SEC_TYPE"DISCRET-GC1"
SEC"1"
PACK_TYPE"DISCRET-GC1";
"2"
$PN"2"77;
"1"
$PN"1"42;
%"GND"
"1","(-4900,3200)","0","mstr_symbols","I8";
;
SIZE"1B"
VOLTAGE"0.0V"
CDS_LIB"mstr_symbols"
BODY_TYPE"PLUMBING"
HDL_POWER"GND";
"A\NAC"36;
%"POLYSW-D5A6V-2-GP-U"
"1","(-2775,2850)","0","w_hdl","I89";
;
CDS_SEC"1"
CDS_LOCATION"F25W1"
VALUE"POLYSW-D5A6V-2-GP-U"
CONFIG"069.50007.0071"
GROUP"AST2500"
LOCATION"F25W1"
CDS_LMAN_SYM_OUTLINE"-125,50,125,-50"
CDS_LIB"w_hdl"
PART_NUMBER"69.50011.051"
SEC_TYPE"DISCRET-GA1"
SEC"1"
PACK_TYPE"DISCRET-GA1";
"2"
$PN"2"34;
"1"
$PN"1"57;
%"GND"
"1","(-4500,3200)","0","mstr_symbols","I9";
;
CDS_LIB"mstr_symbols"
VOLTAGE"0.0V"
SIZE"1B"
BODY_TYPE"PLUMBING"
HDL_POWER"GND";
"A\NAC"37;
%"W_VCC_CIRCLE"
"1","(-4150,2800)","0","w_power","I91";
;
HDL_POWER"P5V_VGA_D"
CDS_LMAN_SYM_OUTLINE"-100,100,100,-100"
CDS_LIB"w_power"
BODY_TYPE"PLUMBING";
"VCC_CIRCLE \B"38;
%"FET_N_DUAL"
"5","(-8100,4750)","5","mstr_discrete","I95";
;
GROUP"AST2500"
VALUE"2N7002DW"
LOCATION"Q25W4"
PART_NUMBER"D24280-001"
MATERIAL"FET"
SEC_TYPE"SMLF"
SEC"1"
PACK_TYPE"SMLF"
CDS_LIB"mstr_discrete"
BOM_COST"DEBUG"
ROOM"UART_MUX"
CDS_SEC"1"
CDS_LOCATION"Q25W4";
"GATE <SIZE -1..0>"
$PN"2"60;
"SOURCE <SIZE-1..0>"
$PN"1"59;
"DRAIN <SIZE -1..0>"
$PN"6"73;
%"FET_N_DUAL"
"5","(-8100,3500)","5","mstr_discrete","I96";
;
CDS_SEC"2"
GROUP"AST2500"
PART_NUMBER"D24280-001"
LOCATION"Q25W4"
VALUE"2N7002DW"
MATERIAL"FET"
PACK_TYPE"SMLF"
SEC"2"
SEC_TYPE"SMLF"
CDS_LIB"mstr_discrete"
BOM_COST"DEBUG"
ROOM"UART_MUX"
CDS_LOCATION"Q25W4";
"GATE <SIZE -1..0>"
$PN"5"61;
"SOURCE <SIZE-1..0>"
$PN"4"51;
"DRAIN <SIZE -1..0>"
$PN"3"52;
END.
